#ISCELL
  mstr_misc dns *
  *
#ISCELL
  pure_quanta quanta_title_block_c *
  *
#ISCELL
  pure_quanta_power cad_note *
  *
#CELL
  pure_quanta q_cap *
  page454_i10
#CELL
  pure_quanta q_cap *
  page454_i100
#CELL
  pure_quanta q_capp *
  page454_i101
#CELL
  pure_quanta q_cap *
  page454_i102
#CELL
  pure_quanta q_cap *
  page454_i103
#CELL
  pure_quanta q_cap *
  page454_i104
#CELL
  pure_quanta q_cap *
  page454_i105
#CELL
  pure_quanta q_cap *
  page454_i11
#CELL
  pure_quanta q_cap *
  page454_i12
#CELL
  pure_quanta q_cap *
  page454_i13
#ISCELL
  pure_quanta_power universal_gnd *
  page454_i14
#CELL
  pure_quanta q_cap *
  page454_i15
#CELL
  pure_quanta q_cap *
  page454_i16
#CELL
  pure_quanta q_cap *
  page454_i17
#CELL
  pure_quanta q_cap *
  page454_i18
#CELL
  pure_quanta q_cap *
  page454_i19
#CELL
  pure_quanta q_res *
  page454_i2
#CELL
  pure_quanta q_res *
  page454_i20
#CELL
  pure_quanta q_inductor *
  page454_i21
#ISCELL
  pure_quanta_power p1v0 *
  page454_i22
#ISCELL
  pure_quanta_power p1v0 *
  page454_i23
#CELL
  pure_quanta q_cap *
  page454_i24
#CELL
  pure_quanta q_cap *
  page454_i25
#ISCELL
  pure_quanta_power universal_gnd *
  page454_i26
#CELL
  pure_quanta q_cap *
  page454_i27
#CELL
  pure_quanta q_cap *
  page454_i28
#ISCELL
  pure_quanta_power vcc_core *
  page454_i29
#CELL
  pure_quanta q_res *
  page454_i3
#ISCELL
  pure_quanta_power vcc_core *
  page454_i30
#CELL
  pure_quanta q_cap *
  page454_i31
#ISCELL
  pure_quanta_power universal_gnd *
  page454_i34
#CELL
  pure_quanta q_cap *
  page454_i35
#CELL
  pure_quanta q_cap *
  page454_i36
#CELL
  pure_quanta q_cap *
  page454_i37
#CELL
  pure_quanta q_cap *
  page454_i38
#CELL
  pure_quanta q_cap *
  page454_i39
#CELL
  pure_quanta q_cap *
  page454_i40
#CELL
  pure_quanta q_res *
  page454_i41
#CELL
  pure_quanta q_cap *
  page454_i42
#CELL
  pure_quanta q_cap *
  page454_i43
#CELL
  pure_quanta q_cap *
  page454_i44
#CELL
  pure_quanta q_cap *
  page454_i45
#CELL
  pure_quanta q_cap *
  page454_i46
#CELL
  pure_quanta q_cap *
  page454_i47
#CELL
  pure_quanta q_cap *
  page454_i48
#CELL
  pure_quanta q_cap *
  page454_i49
#CELL
  pure_quanta q_cap *
  page454_i5
#CELL
  pure_quanta q_cap *
  page454_i50
#CELL
  pure_quanta q_cap *
  page454_i51
#CELL
  pure_quanta q_cap *
  page454_i52
#CELL
  pure_quanta q_cap *
  page454_i53
#CELL
  pure_quanta q_cap *
  page454_i54
#CELL
  pure_quanta q_cap *
  page454_i55
#CELL
  pure_quanta q_cap *
  page454_i56
#CELL
  pure_quanta q_cap *
  page454_i57
#CELL
  pure_quanta q_cap *
  page454_i58
#CELL
  pure_quanta q_cap *
  page454_i59
#CELL
  pure_quanta q_cap *
  page454_i6
#CELL
  pure_quanta q_cap *
  page454_i60
#CELL
  pure_quanta q_cap *
  page454_i61
#CELL
  pure_quanta q_cap *
  page454_i62
#ISCELL
  pure_quanta_power universal_gnd *
  page454_i63
#CELL
  pure_quanta q_cap *
  page454_i64
#CELL
  pure_quanta q_cap *
  page454_i67
#CELL
  pure_quanta q_cap *
  page454_i68
#CELL
  pure_quanta q_cap *
  page454_i69
#ISCELL
  pure_quanta_power universal_gnd *
  page454_i7
#CELL
  pure_quanta q_cap *
  page454_i70
#CELL
  pure_quanta q_cap *
  page454_i71
#CELL
  pure_quanta q_cap *
  page454_i72
#ISCELL
  pure_quanta_power universal_gnd *
  page454_i73
#CELL
  pure_quanta q_inductor *
  page454_i74
#ISCELL
  pure_quanta_power vcc_core *
  page454_i75
#CELL
  pure_quanta q_cap *
  page454_i76
#CELL
  pure_quanta q_cap *
  page454_i77
#CELL
  pure_quanta q_cap *
  page454_i78
#CELL
  pure_quanta q_cap *
  page454_i79
#CELL
  pure_quanta q_cap *
  page454_i8
#CELL
  pure_quanta q_cap *
  page454_i80
#ISCELL
  pure_quanta_power universal_gnd *
  page454_i81
#CELL
  pure_quanta q_cap *
  page454_i82
#CELL
  pure_quanta q_cap *
  page454_i83
#CELL
  pure_quanta q_cap *
  page454_i84
#CELL
  pure_quanta q_cap *
  page454_i85
#CELL
  pure_quanta q_cap *
  page454_i86
#CELL
  pure_quanta q_cap *
  page454_i87
#CELL
  pure_quanta q_inductor *
  page454_i88
#CELL
  pure_quanta q_res *
  page454_i89
#ISCELL
  pure_quanta_power p1v0 *
  page454_i9
#CELL
  pure_quanta q_cap *
  page454_i90
#CELL
  pure_quanta q_cap *
  page454_i91
#CELL
  pure_quanta q_cap *
  page454_i92
#CELL
  pure_quanta q_cap *
  page454_i93
#CELL
  pure_quanta q_capp *
  page454_i94
#CELL
  pure_quanta q_capp *
  page454_i95
#CELL
  pure_quanta q_cap *
  page454_i96
#CELL
  pure_quanta q_cap *
  page454_i97
#CELL
  pure_quanta q_capp *
  page454_i98
#CELL
  pure_quanta q_capp *
  page454_i99
